# T6G (Grand Teton) — schematic parts with pin connectivity, parts 8081–8081 of 8303; source: Cadence DE-HDL packaged netlist (pstxprt.dat, pstxnet.dat, pstchip.dat)

U25  GENOA_SP5  SOCKET6096_13568-001 IO  pkg SOCKET6096_93-4X120-45XA  page 10  (pins 1681-2016 of 6096)
  BC58  VSS_BC58  POWER  = GND
  BC59  MDA_PAR  OUT  = M_D_CPU0_SA_PAR
  BC60  MD0_CLK_H  OUT  = M_D_CPU0_CLK_DP<0>
  BC61  VSS_BC61  POWER  = GND
  BC62  MBA_PAR  OUT  = M_B_CPU0_SA_PAR
  BC63  VSS_BC63  POWER  = GND
  BC64  MB0_CLK_H  OUT  = M_B_CPU0_CLK_DP<0>
  BC65  VSS_BC65  POWER  = GND
  BC66  MFA_PAR  OUT  = M_F_CPU0_SA_PAR
  BC67  MF0_CLK_H  OUT  = M_F_CPU0_CLK_DP<0>
  BC68  VSS_BC68  POWER  = GND
  BC69  MEA_PAR  OUT  = M_E_CPU0_SA_PAR
  BC70  VSS_BC70  POWER  = GND
  BC71  ME0_CLK_H  OUT  = M_E_CPU0_CLK_DP<0>
  BC72  VSS_BC72  POWER  = GND
  BC73  MAA_PAR  OUT  = M_A_CPU0_SA_PAR
  BC74  MA0_CLK_H  OUT  = M_A_CPU0_CLK_DP<0>
  BC75  VSS_BC75  POWER  = GND
  BD2  MG0_CLK_L  OUT  = M_G_CPU0_CLK_DN<0>
  BD3  VSS_BD3  POWER  = GND
  BD4  RSVD_BD4  TRI  = NC
  BD5  VDDCR_SOC_BD5  POWER  = PVDDCR_SOC_P0
  BD6  MK0_CLK_L  OUT  = M_K_CPU0_CLK_DN<0>
  BD7  RSVD_BD7  TRI  = NC
  BD8  VSS_BD8  POWER  = GND
  BD9  ML0_CLK_L  OUT  = M_L_CPU0_CLK_DN<0>
  BD10  VSS_BD10  POWER  = GND
  BD11  RSVD_BD11  TRI  = NC
  BD12  VDDCR_SOC_BD12  POWER  = PVDDCR_SOC_P0
  BD13  MH0_CLK_L  OUT  = M_H_CPU0_CLK_DN<0>
  BD14  RSVD_BD14  TRI  = NC
  BD15  VSS_BD15  POWER  = GND
  BD16  MJ0_CLK_L  OUT  = M_J_CPU0_CLK_DN<0>
  BD17  VSS_BD17  POWER  = GND
  BD18  RSVD_BD18  TRI  = NC
  BD19  VDDCR_SOC_BD19  POWER  = PVDDCR_SOC_P0
  BD20  MI0_CLK_L  OUT  = M_I_CPU0_CLK_DN<0>
  BD21  RSVD_BD21  TRI  = NC
  BD22  VDDCR_SOC_BD22  POWER  = PVDDCR_SOC_P0
  BD23  VSS_BD23  POWER  = GND
  BD24  VDDCR_SOC_BD24  POWER  = PVDDCR_SOC_P0
  BD25  VSS_BD25  POWER  = GND
  BD26  VDDCR_SOC_BD26  POWER  = PVDDCR_SOC_P0
  BD27  VSS_BD27  POWER  = GND
  BD28  VDDCR_SOC_BD28  POWER  = PVDDCR_SOC_P0
  BD48  VDDCR_SOC_BD48  POWER  = PVDDCR_SOC_P0
  BD49  VSS_BD49  POWER  = GND
  BD50  VDDIO_BD50  POWER  = PVDDIO_P0
  BD51  VSS_BD51  POWER  = GND
  BD52  VDDIO_BD52  POWER  = PVDDIO_P0
  BD53  VSS_BD53  POWER  = GND
  BD54  VDDIO_BD54  POWER  = PVDDIO_P0
  BD55  RSVD_BD55  TRI  = NC
  BD56  MC0_CLK_L  OUT  = M_C_CPU0_CLK_DN<0>
  BD57  VSS_BD57  POWER  = GND
  BD58  RSVD_BD58  TRI  = NC
  BD59  VSS_BD59  POWER  = GND
  BD60  MD0_CLK_L  OUT  = M_D_CPU0_CLK_DN<0>
  BD61  VSS_BD61  POWER  = GND
  BD62  RSVD_BD62  TRI  = NC
  BD63  MB0_CLK_L  OUT  = M_B_CPU0_CLK_DN<0>
  BD64  VSS_BD64  POWER  = GND
  BD65  RSVD_BD65  TRI  = NC
  BD66  VSS_BD66  POWER  = GND
  BD67  MF0_CLK_L  OUT  = M_F_CPU0_CLK_DN<0>
  BD68  VSS_BD68  POWER  = GND
  BD69  RSVD_BD69  TRI  = NC
  BD70  ME0_CLK_L  OUT  = M_E_CPU0_CLK_DN<0>
  BD71  VSS_BD71  POWER  = GND
  BD72  RSVD_BD72  TRI  = NC
  BD73  VSS_BD73  POWER  = GND
  BD74  MA0_CLK_L  OUT  = M_A_CPU0_CLK_DN<0>
  BF2  MG1_CLK_H  OUT  = NC
  BF3  VSS_BF3  POWER  = GND
  BF4  TEST39G  OUT  = TP_M_G_CPU0_SA_TEST39G
  BF5  VSS_BF5  POWER  = GND
  BF6  MK1_CLK_H  OUT  = NC
  BF7  TEST39K  OUT  = TP_M_K_CPU0_SA_TEST39K
  BF8  VSS_BF8  POWER  = GND
  BF9  ML1_CLK_H  OUT  = NC
  BF10  VSS_BF10  POWER  = GND
  BF11  TEST39L  OUT  = TP_M_L_CPU0_SA_TEST39L
  BF12  VSS_BF12  POWER  = GND
  BF13  MH1_CLK_H  OUT  = NC
  BF14  TEST39H  OUT  = TP_M_H_CPU0_SA_TEST39H
  BF15  VSS_BF15  POWER  = GND
  BF16  MJ1_CLK_H  OUT  = NC
  BF17  VSS_BF17  POWER  = GND
  BF18  TEST39J  OUT  = TP_M_J_CPU0_SA_TEST39J
  BF19  VSS_BF19  POWER  = GND
  BF20  MI1_CLK_H  OUT  = NC
  BF21  TEST39I  OUT  = TP_M_I_CPU0_SA_TEST39I
  BF22  VSS_BF22  POWER  = GND
  BF23  VDDCR_SOC_BF23  POWER  = PVDDCR_SOC_P0
  BF24  VSS_BF24  POWER  = GND
  BF25  VDDCR_SOC_BF25  POWER  = PVDDCR_SOC_P0
  BF26  VSS_BF26  POWER  = GND
  BF27  VDDCR_SOC_BF27  POWER  = PVDDCR_SOC_P0
  BF28  VSS_BF28  POWER  = GND
  BF48  VDDCR_SOC_BF48  POWER  = PVDDCR_SOC_P0
  BF49  VSS_BF49  POWER  = GND
  BF50  VSS_BF50  POWER  = GND
  BF51  VDDIO_BF51  POWER  = PVDDIO_P0
  BF52  VSS_BF52  POWER  = GND
  BF53  VDDIO_BF53  POWER  = PVDDIO_P0
  BF54  VSS_BF54  POWER  = GND
  BF55  TEST39C  OUT  = TP_M_C_CPU0_SA_TEST39C
  BF56  MC1_CLK_H  OUT  = NC
  BF57  VDDIO_BF57  POWER  = PVDDIO_P0
  BF58  TEST39D  OUT  = TP_M_D_CPU0_SA_TEST39D
  BF59  VSS_BF59  POWER  = GND
  BF60  MD1_CLK_H  OUT  = NC
  BF61  VSS_BF61  POWER  = GND
  BF62  TEST39B  OUT  = TP_M_B_CPU0_SA_TEST39B
  BF63  MB1_CLK_H  OUT  = NC
  BF64  VDDIO_BF64  POWER  = PVDDIO_P0
  BF65  TEST39F  OUT  = TP_M_F_CPU0_SA_TEST39F
  BF66  VSS_BF66  POWER  = GND
  BF67  MF1_CLK_H  OUT  = NC
  BF68  VSS_BF68  POWER  = GND
  BF69  TEST39E  OUT  = TP_M_E_CPU0_SA_TEST39E
  BF70  ME1_CLK_H  OUT  = NC
  BF71  VDDIO_BF71  POWER  = PVDDIO_P0
  BF72  TEST39A  OUT  = TP_M_A_CPU0_SA_TEST39A
  BF73  VSS_BF73  POWER  = GND
  BF74  MA1_CLK_H  OUT  = NC
  BG1  VSS_BG1  POWER  = GND
  BG2  MG1_CLK_L  OUT  = NC
  BG3  MGB_CA0  OUT  = M_G_CPU0_SB_CA<0>
  BG4  VSS_BG4  POWER  = GND
  BG5  MK1_CLK_L  OUT  = NC
  BG6  VSS_BG6  POWER  = GND
  BG7  MKB_CA0  OUT  = M_K_CPU0_SB_CA<0>
  BG8  VSS_BG8  POWER  = GND
  BG9  ML1_CLK_L  OUT  = NC
  BG10  MLB_CA0  OUT  = M_L_CPU0_SB_CA<0>
  BG11  VSS_BG11  POWER  = GND
  BG12  MH1_CLK_L  OUT  = NC
  BG13  VSS_BG13  POWER  = GND
  BG14  MHB_CA0  OUT  = M_H_CPU0_SB_CA<0>
  BG15  VSS_BG15  POWER  = GND
  BG16  MJ1_CLK_L  OUT  = NC
  BG17  MJB_CA0  OUT  = M_J_CPU0_SB_CA<0>
  BG18  VSS_BG18  POWER  = GND
  BG19  MI1_CLK_L  OUT  = NC
  BG20  VSS_BG20  POWER  = GND
  BG21  MIB_CA0  OUT  = M_I_CPU0_SB_CA<0>
  BG22  VDDCR_SOC_BG22  POWER  = PVDDCR_SOC_P0
  BG23  VSS_BG23  POWER  = GND
  BG24  VDDCR_SOC_BG24  POWER  = PVDDCR_SOC_P0
  BG25  VSS_BG25  POWER  = GND
  BG26  VDDCR_SOC_BG26  POWER  = PVDDCR_SOC_P0
  BG27  VSS_BG27  POWER  = GND
  BG28  VDDCR_SOC_BG28  POWER  = PVDDCR_SOC_P0
  BG48  VDDCR_SOC_BG48  POWER  = PVDDCR_SOC_P0
  BG49  VSS_BG49  POWER  = GND
  BG50  VDDIO_BG50  POWER  = PVDDIO_P0
  BG51  VSS_BG51  POWER  = GND
  BG52  VDDIO_BG52  POWER  = PVDDIO_P0
  BG53  VSS_BG53  POWER  = GND
  BG54  VDDIO_BG54  POWER  = PVDDIO_P0
  BG55  MCB_CA0  OUT  = M_C_CPU0_SB_CA<0>
  BG56  VSS_BG56  POWER  = GND
  BG57  MC1_CLK_L  OUT  = NC
  BG58  VSS_BG58  POWER  = GND
  BG59  MDB_CA0  OUT  = M_D_CPU0_SB_CA<0>
  BG60  MD1_CLK_L  OUT  = NC
  BG61  VSS_BG61  POWER  = GND
  BG62  MBB_CA0  OUT  = M_B_CPU0_SB_CA<0>
  BG63  VSS_BG63  POWER  = GND
  BG64  MB1_CLK_L  OUT  = NC
  BG65  VSS_BG65  POWER  = GND
  BG66  MFB_CA0  OUT  = M_F_CPU0_SB_CA<0>
  BG67  MF1_CLK_L  OUT  = NC
  BG68  VSS_BG68  POWER  = GND
  BG69  MEB_CA0  OUT  = M_E_CPU0_SB_CA<0>
  BG70  VSS_BG70  POWER  = GND
  BG71  ME1_CLK_L  OUT  = NC
  BG72  VSS_BG72  POWER  = GND
  BG73  MAB_CA0  OUT  = M_A_CPU0_SB_CA<0>
  BG74  MA1_CLK_L  OUT  = NC
  BG75  VSS_BG75  POWER  = GND
  BH2  MGB_CA2  OUT  = M_G_CPU0_SB_CA<2>
  BH3  VSS_BH3  POWER  = GND
  BH4  MGB_CA1  OUT  = M_G_CPU0_SB_CA<1>
  BH5  VSS_BH5  POWER  = GND
  BH6  MKB_CA2  OUT  = M_K_CPU0_SB_CA<2>
  BH7  MKB_CA1  OUT  = M_K_CPU0_SB_CA<1>
  BH8  VSS_BH8  POWER  = GND
  BH9  MLB_CA2  OUT  = M_L_CPU0_SB_CA<2>
  BH10  VSS_BH10  POWER  = GND
  BH11  MLB_CA1  OUT  = M_L_CPU0_SB_CA<1>
  BH12  VSS_BH12  POWER  = GND
  BH13  MHB_CA2  OUT  = M_H_CPU0_SB_CA<2>
  BH14  MHB_CA1  OUT  = M_H_CPU0_SB_CA<1>
  BH15  VSS_BH15  POWER  = GND
  BH16  MJB_CA2  OUT  = M_J_CPU0_SB_CA<2>
  BH17  VSS_BH17  POWER  = GND
  BH18  MJB_CA1  OUT  = M_J_CPU0_SB_CA<1>
  BH19  VSS_BH19  POWER  = GND
  BH20  MIB_CA2  OUT  = M_I_CPU0_SB_CA<2>
  BH21  MIB_CA1  OUT  = M_I_CPU0_SB_CA<1>
  BH22  VSS_BH22  POWER  = GND
  BH23  VDDCR_SOC_BH23  POWER  = PVDDCR_SOC_P0
  BH24  VSS_BH24  POWER  = GND
  BH25  VDDCR_SOC_BH25  POWER  = PVDDCR_SOC_P0
  BH26  VSS_BH26  POWER  = GND
  BH27  VDDIO_AUDIO  POWER  = PVDD18_S5_P0
  BH28  VSS_BH28  POWER  = GND
  BH48  VDDCR_SOC_BH48  POWER  = PVDDCR_SOC_P0
  BH49  VSS_BH49  POWER  = GND
  BH50  VSS_BH50  POWER  = GND
  BH51  VDDIO_BH51  POWER  = PVDDIO_P0
  BH52  VSS_BH52  POWER  = GND
  BH53  VDDIO_BH53  POWER  = PVDDIO_P0
  BH54  VSS_BH54  POWER  = GND
  BH55  MCB_CA1  OUT  = M_C_CPU0_SB_CA<1>
  BH56  MCB_CA2  OUT  = M_C_CPU0_SB_CA<2>
  BH57  VSS_BH57  POWER  = GND
  BH58  MDB_CA1  OUT  = M_D_CPU0_SB_CA<1>
  BH59  VSS_BH59  POWER  = GND
  BH60  MDB_CA2  OUT  = M_D_CPU0_SB_CA<2>
  BH61  VSS_BH61  POWER  = GND
  BH62  MBB_CA1  OUT  = M_B_CPU0_SB_CA<1>
  BH63  MBB_CA2  OUT  = M_B_CPU0_SB_CA<2>
  BH64  VSS_BH64  POWER  = GND
  BH65  MFB_CA1  OUT  = M_F_CPU0_SB_CA<1>
  BH66  VSS_BH66  POWER  = GND
  BH67  MFB_CA2  OUT  = M_F_CPU0_SB_CA<2>
  BH68  VSS_BH68  POWER  = GND
  BH69  MEB_CA1  OUT  = M_E_CPU0_SB_CA<1>
  BH70  MEB_CA2  OUT  = M_E_CPU0_SB_CA<2>
  BH71  VSS_BH71  POWER  = GND
  BH72  MAB_CA1  OUT  = M_A_CPU0_SB_CA<1>
  BH73  VSS_BH73  POWER  = GND
  BH74  MAB_CA2  OUT  = M_A_CPU0_SB_CA<2>
  BJ1  VSS_BJ1  POWER  = GND
  BJ2  MGB_CA3  OUT  = M_G_CPU0_SB_CA<3>
  BJ3  MGB_CA4  OUT  = M_G_CPU0_SB_CA<4>
  BJ4  VDDCR_SOC_BJ4  POWER  = PVDDCR_SOC_P0
  BJ5  MKB_CA3  OUT  = M_K_CPU0_SB_CA<3>
  BJ6  VSS_BJ6  POWER  = GND
  BJ7  MKB_CA4  OUT  = M_K_CPU0_SB_CA<4>
  BJ8  VSS_BJ8  POWER  = GND
  BJ9  MLB_CA3  OUT  = M_L_CPU0_SB_CA<3>
  BJ10  MLB_CA4  OUT  = M_L_CPU0_SB_CA<4>
  BJ11  VDDCR_SOC_BJ11  POWER  = PVDDCR_SOC_P0
  BJ12  MHB_CA3  OUT  = M_H_CPU0_SB_CA<3>
  BJ13  VSS_BJ13  POWER  = GND
  BJ14  MHB_CA4  OUT  = M_H_CPU0_SB_CA<4>
  BJ15  VSS_BJ15  POWER  = GND
  BJ16  MJB_CA3  OUT  = M_J_CPU0_SB_CA<3>
  BJ17  MJB_CA4  OUT  = M_J_CPU0_SB_CA<4>
  BJ18  VDD_11_S3_BJ18  POWER  = PVDD11_S3_P0
  BJ19  MIB_CA3  OUT  = M_I_CPU0_SB_CA<3>
  BJ20  VSS_BJ20  POWER  = GND
  BJ21  MIB_CA4  OUT  = M_I_CPU0_SB_CA<4>
  BJ22  VSS_BJ22  POWER  = GND
  BJ23  VDD_11_S3_BJ23  POWER  = PVDD11_S3_P0
  BJ24  VSS_BJ24  POWER  = GND
  BJ25  VDD_11_S3_BJ25  POWER  = PVDD11_S3_P0
  BJ26  VSS_BJ26  POWER  = GND
  BJ27  VDD_11_S3_BJ27  POWER  = PVDD11_S3_P0
  BJ28  VSS_BJ28  POWER  = GND
  BJ48  VDDCR_SOC_BJ48  POWER  = PVDDCR_SOC_P0
  BJ49  VSS_BJ49  POWER  = GND
  BJ50  VDDIO_BJ50  POWER  = PVDDIO_P0
  BJ51  VSS_BJ51  POWER  = GND
  BJ52  VDDIO_BJ52  POWER  = PVDDIO_P0
  BJ53  VSS_BJ53  POWER  = GND
  BJ54  VDDIO_BJ54  POWER  = PVDDIO_P0
  BJ55  MCB_CA4  OUT  = M_C_CPU0_SB_CA<4>
  BJ56  VSS_BJ56  POWER  = GND
  BJ57  MCB_CA3  OUT  = M_C_CPU0_SB_CA<3>
  BJ58  VDDIO_BJ58  POWER  = PVDDIO_P0
  BJ59  MDB_CA4  OUT  = M_D_CPU0_SB_CA<4>
  BJ60  MDB_CA3  OUT  = M_D_CPU0_SB_CA<3>
  BJ61  VSS_BJ61  POWER  = GND
  BJ62  MBB_CA4  OUT  = M_B_CPU0_SB_CA<4>
  BJ63  VSS_BJ63  POWER  = GND
  BJ64  MBB_CA3  OUT  = M_B_CPU0_SB_CA<3>
  BJ65  VDDIO_BJ65  POWER  = PVDDIO_P0
  BJ66  MFB_CA4  OUT  = M_F_CPU0_SB_CA<4>
  BJ67  MFB_CA3  OUT  = M_F_CPU0_SB_CA<3>
  BJ68  VSS_BJ68  POWER  = GND
  BJ69  MEB_CA4  OUT  = M_E_CPU0_SB_CA<4>
  BJ70  VSS_BJ70  POWER  = GND
  BJ71  MEB_CA3  OUT  = M_E_CPU0_SB_CA<3>
  BJ72  VDDIO_BJ72  POWER  = PVDDIO_P0
  BJ73  MAB_CA4  OUT  = M_A_CPU0_SB_CA<4>
  BJ74  MAB_CA3  OUT  = M_A_CPU0_SB_CA<3>
  BJ75  VSS_BJ75  POWER  = GND
  BK2  MGB_CA6  OUT  = M_G_CPU0_SB_CA<6>
  BK3  VSS_BK3  POWER  = GND
  BK4  MGB_CA5  OUT  = M_G_CPU0_SB_CA<5>
  BK5  VSS_BK5  POWER  = GND
  BK6  MKB_CA6  OUT  = M_K_CPU0_SB_CA<6>
  BK7  MKB_CA5  OUT  = M_K_CPU0_SB_CA<5>
  BK8  VSS_BK8  POWER  = GND
  BK9  MLB_CA6  OUT  = M_L_CPU0_SB_CA<6>
  BK10  VSS_BK10  POWER  = GND
  BK11  MLB_CA5  OUT  = M_L_CPU0_SB_CA<5>
  BK12  VSS_BK12  POWER  = GND
  BK13  MHB_CA6  OUT  = M_H_CPU0_SB_CA<6>
  BK14  MHB_CA5  OUT  = M_H_CPU0_SB_CA<5>
  BK15  VSS_BK15  POWER  = GND
  BK16  MJB_CA6  OUT  = M_J_CPU0_SB_CA<6>
  BK17  VSS_BK17  POWER  = GND
  BK18  MJB_CA5  OUT  = M_J_CPU0_SB_CA<5>
  BK19  VSS_BK19  POWER  = GND
  BK20  MIB_CA6  OUT  = M_I_CPU0_SB_CA<6>
  BK21  MIB_CA5  OUT  = M_I_CPU0_SB_CA<5>
  BK22  VDD_11_S3_BK22  POWER  = PVDD11_S3_P0
  BK23  VSS_BK23  POWER  = GND
  BK24  VDD_11_S3_BK24  POWER  = PVDD11_S3_P0
  BK25  VSS_BK25  POWER  = GND
  BK26  VDD_11_S3_BK26  POWER  = PVDD11_S3_P0
  BK27  VSS_BK27  POWER  = GND
  BK28  VDD_11_S3_BK28  POWER  = PVDD11_S3_P0
  BK48  VSS_BK48  POWER  = GND
  BK49  VDD_11_S3_BK49  POWER  = PVDD11_S3_P0
  BK50  VSS_BK50  POWER  = GND
  BK51  VDDIO_BK51  POWER  = PVDDIO_P0
  BK52  VSS_BK52  POWER  = GND
  BK53  VDDIO_BK53  POWER  = PVDDIO_P0
  BK54  VSS_BK54  POWER  = GND
  BK55  MCB_CA5  OUT  = M_C_CPU0_SB_CA<5>
  BK56  MCB_CA6  OUT  = M_C_CPU0_SB_CA<6>
  BK57  VSS_BK57  POWER  = GND
  BK58  MDB_CA5  OUT  = M_D_CPU0_SB_CA<5>
  BK59  VSS_BK59  POWER  = GND
  BK60  MDB_CA6  OUT  = M_D_CPU0_SB_CA<6>
  BK61  VSS_BK61  POWER  = GND
  BK62  MBB_CA5  OUT  = M_B_CPU0_SB_CA<5>
  BK63  MBB_CA6  OUT  = M_B_CPU0_SB_CA<6>
  BK64  VSS_BK64  POWER  = GND
